(kicad_pcb
	(version 20260206)
	(generator "pcbnew")
	(generator_version "10.0")
	(general
		(thickness 1.6)
		(legacy_teardrops no)
	)
	(paper "A4")
	(title_block
		(title "12092022_DA0F0TMDCD0_F0T_Management_Board_D_brd_V3_OCP.brd")
		(comment 1 "Grand Teton / footprints 479-484 of 1440")
	)
	(layers
		(0 "F.Cu" signal "TOP")
		(4 "In1.Cu" signal "GND")
		(6 "In2.Cu" signal "IN1")
		(8 "In3.Cu" signal "GND1")
		(10 "In4.Cu" signal "IN2")
		(12 "In5.Cu" signal "VCC")
		(14 "In6.Cu" signal "VCC1")
		(16 "In7.Cu" signal "IN3")
		(18 "In8.Cu" signal "GND2")
		(20 "In9.Cu" signal "IN4")
		(22 "In10.Cu" signal "GND3")
		(2 "B.Cu" signal "BOTTOM")
		(9 "F.Adhes" user "F.Adhesive")
		(11 "B.Adhes" user "B.Adhesive")
		(13 "F.Paste" user "Package Geometry/Pastemask Top")
		(15 "B.Paste" user "Package Geometry/Pastemask Bottom")
		(5 "F.SilkS" user "Ref Des/Silkscreen Top")
		(7 "B.SilkS" user "Ref Des/Silkscreen Bottom")
		(1 "F.Mask" user "Board Geometry/Soldermask Top")
		(3 "B.Mask" user "Board Geometry/Soldermask Bottom")
		(17 "Dwgs.User" user "User.Drawings")
		(19 "Cmts.User" user "User.Comments")
		(21 "Eco1.User" user "User.Eco1")
		(23 "Eco2.User" user "User.Eco2")
		(25 "Edge.Cuts" user "Board Geometry/Outline")
		(27 "Margin" user)
		(31 "F.CrtYd" user "Package Geometry/Place Bound Top")
		(29 "B.CrtYd" user "Package Geometry/Place Bound Bottom")
		(35 "F.Fab" user "Ref Des/Assembly Top")
		(33 "B.Fab" user "Ref Des/Assembly Bottom")
	)
	(footprint ""
		(layer "F.Cu")
		(at 61.469016 -79.632556)
		(property "Reference" "R624"
			(at 0 0 0)
			(layer "F.SilkS")
			(hide yes)
			(effects
				(font
					(size 1.27 1.27)
				)
			)
		)
		(property "Value" ""
			(at 0 0 0)
			(layer "F.Fab")
			(effects
				(font
					(size 1.27 1.27)
				)
			)
		)
		(duplicate_pad_numbers_are_jumpers no)
		(fp_line
			(start -0.7874 -0.4064)
			(end 0.7874 -0.4064)
			(stroke
				(width 0.1524)
				(type default)
			)
			(layer "F.SilkS")
		)
		(fp_line
			(start -0.7874 0.4064)
			(end -0.7874 -0.4064)
			(stroke
				(width 0.1524)
				(type default)
			)
			(layer "F.SilkS")
		)
		(fp_line
			(start 0.7874 -0.4064)
			(end 0.7874 0.4064)
			(stroke
				(width 0.1524)
				(type default)
			)
			(layer "F.SilkS")
		)
		(fp_line
			(start 0.7874 0.4064)
			(end -0.7874 0.4064)
			(stroke
				(width 0.1524)
				(type default)
			)
			(layer "F.SilkS")
		)
		(fp_line
			(start -0.67945 -0.305054)
			(end -0.12065 -0.305054)
			(stroke
				(width 0.1)
				(type default)
			)
			(layer "F.Fab")
		)
		(fp_line
			(start -0.67945 0.3048)
			(end -0.67945 -0.305054)
			(stroke
				(width 0.1)
				(type default)
			)
			(layer "F.Fab")
		)
		(fp_line
			(start -0.12065 -0.305054)
			(end -0.12065 -0.2794)
			(stroke
				(width 0.1)
				(type default)
			)
			(layer "F.Fab")
		)
		(fp_line
			(start -0.12065 -0.2794)
			(end 0.12065 -0.2794)
			(stroke
				(width 0.1)
				(type default)
			)
			(layer "F.Fab")
		)
		(fp_line
			(start -0.12065 0.2794)
			(end -0.12065 0.3048)
			(stroke
				(width 0.1)
				(type default)
			)
			(layer "F.Fab")
		)
		(fp_line
			(start -0.12065 0.3048)
			(end -0.67945 0.3048)
			(stroke
				(width 0.1)
				(type default)
			)
			(layer "F.Fab")
		)
		(fp_line
			(start 0.120396 0.2794)
			(end -0.12065 0.2794)
			(stroke
				(width 0.1)
				(type default)
			)
			(layer "F.Fab")
		)
		(fp_line
			(start 0.120396 0.3048)
			(end 0.120396 0.2794)
			(stroke
				(width 0.1)
				(type default)
			)
			(layer "F.Fab")
		)
		(fp_line
			(start 0.12065 -0.3048)
			(end 0.67945 -0.3048)
			(stroke
				(width 0.1)
				(type default)
			)
			(layer "F.Fab")
		)
		(fp_line
			(start 0.12065 -0.2794)
			(end 0.12065 -0.3048)
			(stroke
				(width 0.1)
				(type default)
			)
			(layer "F.Fab")
		)
		(fp_line
			(start 0.67945 -0.3048)
			(end 0.67945 0.3048)
			(stroke
				(width 0.1)
				(type default)
			)
			(layer "F.Fab")
		)
		(fp_line
			(start 0.67945 0.3048)
			(end 0.120396 0.3048)
			(stroke
				(width 0.1)
				(type default)
			)
			(layer "F.Fab")
		)
		(pad "1" smd circle
			(at -0.40005 0)
			(size 0 0)
			(layers "F.Cu" "F.Mask" "F.Paste")
			(net "P3V3_AUX")
		)
		(pad "2" smd circle
			(at 0.40005 0)
			(size 0 0)
			(layers "F.Cu" "F.Mask" "F.Paste")
			(net "FM_BMC_DEBUG_SW_N")
		)
	)
	(footprint ""
		(layer "F.Cu")
		(at 46.586902 -63.934594 -90)
		(property "Reference" "R25"
			(at 0 0 270)
			(layer "F.SilkS")
			(hide yes)
			(effects
				(font
					(size 1.27 1.27)
				)
			)
		)
		(property "Value" ""
			(at 0 0 270)
			(layer "F.Fab")
			(effects
				(font
					(size 1.27 1.27)
				)
			)
		)
		(duplicate_pad_numbers_are_jumpers no)
		(fp_line
			(start -0.7874 0.4064)
			(end -0.7874 -0.4064)
			(stroke
				(width 0.1524)
				(type default)
			)
			(layer "F.SilkS")
		)
		(fp_line
			(start 0.7874 0.4064)
			(end -0.7874 0.4064)
			(stroke
				(width 0.1524)
				(type default)
			)
			(layer "F.SilkS")
		)
		(fp_line
			(start -0.7874 -0.4064)
			(end 0.7874 -0.4064)
			(stroke
				(width 0.1524)
				(type default)
			)
			(layer "F.SilkS")
		)
		(fp_line
			(start 0.7874 -0.4064)
			(end 0.7874 0.4064)
			(stroke
				(width 0.1524)
				(type default)
			)
			(layer "F.SilkS")
		)
		(fp_line
			(start -0.67945 0.3048)
			(end -0.67945 -0.305054)
			(stroke
				(width 0.1)
				(type default)
			)
			(layer "F.Fab")
		)
		(fp_line
			(start -0.12065 0.3048)
			(end -0.67945 0.3048)
			(stroke
				(width 0.1)
				(type default)
			)
			(layer "F.Fab")
		)
		(fp_line
			(start 0.120396 0.3048)
			(end 0.120396 0.2794)
			(stroke
				(width 0.1)
				(type default)
			)
			(layer "F.Fab")
		)
		(fp_line
			(start 0.67945 0.3048)
			(end 0.120396 0.3048)
			(stroke
				(width 0.1)
				(type default)
			)
			(layer "F.Fab")
		)
		(fp_line
			(start -0.12065 0.2794)
			(end -0.12065 0.3048)
			(stroke
				(width 0.1)
				(type default)
			)
			(layer "F.Fab")
		)
		(fp_line
			(start 0.120396 0.2794)
			(end -0.12065 0.2794)
			(stroke
				(width 0.1)
				(type default)
			)
			(layer "F.Fab")
		)
		(fp_line
			(start -0.12065 -0.2794)
			(end 0.12065 -0.2794)
			(stroke
				(width 0.1)
				(type default)
			)
			(layer "F.Fab")
		)
		(fp_line
			(start 0.12065 -0.2794)
			(end 0.12065 -0.3048)
			(stroke
				(width 0.1)
				(type default)
			)
			(layer "F.Fab")
		)
		(fp_line
			(start 0.12065 -0.3048)
			(end 0.67945 -0.3048)
			(stroke
				(width 0.1)
				(type default)
			)
			(layer "F.Fab")
		)
		(fp_line
			(start 0.67945 -0.3048)
			(end 0.67945 0.3048)
			(stroke
				(width 0.1)
				(type default)
			)
			(layer "F.Fab")
		)
		(fp_line
			(start -0.67945 -0.305054)
			(end -0.12065 -0.305054)
			(stroke
				(width 0.1)
				(type default)
			)
			(layer "F.Fab")
		)
		(fp_line
			(start -0.12065 -0.305054)
			(end -0.12065 -0.2794)
			(stroke
				(width 0.1)
				(type default)
			)
			(layer "F.Fab")
		)
		(pad "1" smd circle
			(at -0.40005 0 270)
			(size 0 0)
			(layers "F.Cu" "F.Mask" "F.Paste")
			(net "V_DACR_R")
		)
		(pad "2" smd circle
			(at 0.40005 0 270)
			(size 0 0)
			(layers "F.Cu" "F.Mask" "F.Paste")
			(net "GND")
		)
	)
	(footprint ""
		(layer "F.Cu")
		(at 31.75 -31.115 180)
		(property "Reference" "U35"
			(at 1.016 3.30073 0)
			(unlocked yes)
			(layer "F.SilkS")
			(effects
				(font
					(size 0.7874 0.5842)
					(thickness 0.1524)
				)
				(justify left)
			)
		)
		(property "Value" ""
			(at 0 0 180)
			(layer "F.Fab")
			(effects
				(font
					(size 1.27 1.27)
				)
			)
		)
		(duplicate_pad_numbers_are_jumpers no)
		(fp_line
			(start 0.791464 1.287526)
			(end 0.791464 -1.287526)
			(stroke
				(width 0.1524)
				(type default)
			)
			(layer "F.SilkS")
		)
		(fp_line
			(start 0.791464 -1.287526)
			(end -0.791464 -1.287526)
			(stroke
				(width 0.1524)
				(type default)
			)
			(layer "F.SilkS")
		)
		(fp_line
			(start -0.791464 1.287526)
			(end 0.791464 1.287526)
			(stroke
				(width 0.1524)
				(type default)
			)
			(layer "F.SilkS")
		)
		(fp_line
			(start -0.791464 -1.287526)
			(end -0.791464 1.287526)
			(stroke
				(width 0.1524)
				(type default)
			)
			(layer "F.SilkS")
		)
		(fp_poly
			(pts
				(xy -1.651 -1.253998) (xy -1.651 -0.745998) (xy -1.143 -0.999998)
			)
			(stroke
				(width 0)
				(type default)
			)
			(fill yes)
			(layer "F.SilkS")
		)
		(fp_line
			(start 0.537464 1.287526)
			(end 0.537464 -1.287526)
			(stroke
				(width 0.1)
				(type default)
			)
			(layer "F.Fab")
		)
		(fp_line
			(start 0.537464 -1.287526)
			(end -0.537464 -1.287526)
			(stroke
				(width 0.1)
				(type default)
			)
			(layer "F.Fab")
		)
		(fp_line
			(start -0.537464 1.287526)
			(end 0.537464 1.287526)
			(stroke
				(width 0.1)
				(type default)
			)
			(layer "F.Fab")
		)
		(fp_line
			(start -0.537464 -1.287526)
			(end -0.537464 1.287526)
			(stroke
				(width 0.1)
				(type default)
			)
			(layer "F.Fab")
		)
		(fp_poly
			(pts
				(xy -1.651 -1.253998) (xy -1.651 -0.745998) (xy -1.143 -0.999998)
			)
			(stroke
				(width 0)
				(type default)
			)
			(fill yes)
			(layer "F.Fab")
		)
		(pad "1" smd rect
			(at -0.387604 -0.999998 270)
			(size 0.254 0.635)
			(layers "F.Cu" "F.Mask" "F.Paste")
			(net "V_DACB_IO")
		)
		(pad "2" smd rect
			(at -0.387604 -0.499872 270)
			(size 0.254 0.635)
			(layers "F.Cu" "F.Mask" "F.Paste")
			(net "V_DACG_IO")
		)
		(pad "3" smd rect
			(at -0.350012 0 270)
			(size 0.4572 0.6858)
			(layers "F.Cu" "F.Mask" "F.Paste")
			(net "GND")
		)
		(pad "4" smd rect
			(at -0.387604 0.499872 270)
			(size 0.254 0.635)
			(layers "F.Cu" "F.Mask" "F.Paste")
			(net "V_DACR_IO")
		)
		(pad "5" smd rect
			(at -0.387604 0.999998 270)
			(size 0.254 0.635)
			(layers "F.Cu" "F.Mask" "F.Paste")
			(net "TP4")
		)
		(pad "6" smd rect
			(at 0.387604 0.999998 270)
			(size 0.254 0.635)
			(layers "F.Cu" "F.Mask" "F.Paste")
			(net "TP_ESD_VGA_P4")
		)
		(pad "7" smd rect
			(at 0.387604 0.499872 270)
			(size 0.254 0.635)
			(layers "F.Cu" "F.Mask" "F.Paste")
			(net "V_DACR_IO")
		)
		(pad "8" smd rect
			(at 0.412496 0 270)
			(size 0.4572 0.5842)
			(layers "F.Cu" "F.Mask" "F.Paste")
			(net "GND")
		)
		(pad "9" smd rect
			(at 0.387604 -0.499872 270)
			(size 0.254 0.635)
			(layers "F.Cu" "F.Mask" "F.Paste")
			(net "V_DACG_IO")
		)
		(pad "10" smd rect
			(at 0.387604 -0.999998 270)
			(size 0.254 0.635)
			(layers "F.Cu" "F.Mask" "F.Paste")
			(net "V_DACB_IO")
		)
	)
	(footprint ""
		(layer "F.Cu")
		(at 52.578 -79.6544 180)
		(property "Reference" "U55"
			(at 2.8448 1.54813 0)
			(unlocked yes)
			(layer "F.SilkS")
			(effects
				(font
					(size 0.7874 0.5842)
					(thickness 0.1524)
				)
			)
		)
		(property "Value" ""
			(at 0 0 180)
			(layer "F.Fab")
			(effects
				(font
					(size 1.27 1.27)
				)
			)
		)
		(duplicate_pad_numbers_are_jumpers no)
		(fp_line
			(start 1.7018 1.1176)
			(end -1.7018 1.1176)
			(stroke
				(width 0.1524)
				(type default)
			)
			(layer "F.SilkS")
		)
		(fp_line
			(start 1.7018 -1.1176)
			(end 1.7018 1.1176)
			(stroke
				(width 0.1524)
				(type default)
			)
			(layer "F.SilkS")
		)
		(fp_line
			(start 1.7018 -1.1176)
			(end 0.254 -1.1176)
			(stroke
				(width 0.1524)
				(type default)
			)
			(layer "F.SilkS")
		)
		(fp_line
			(start 0.254 -1.1176)
			(end 0 -0.7112)
			(stroke
				(width 0.1524)
				(type default)
			)
			(layer "F.SilkS")
		)
		(fp_line
			(start 0 -0.7112)
			(end -0.254 -1.1176)
			(stroke
				(width 0.1524)
				(type default)
			)
			(layer "F.SilkS")
		)
		(fp_line
			(start -0.254 -1.1176)
			(end -1.7018 -1.1176)
			(stroke
				(width 0.1524)
				(type default)
			)
			(layer "F.SilkS")
		)
		(fp_line
			(start -1.7018 1.1176)
			(end -1.7018 -1.1176)
			(stroke
				(width 0.1524)
				(type default)
			)
			(layer "F.SilkS")
		)
		(fp_poly
			(pts
				(xy -1.8161 -0.675386) (xy -2.4003 -0.446786) (xy -2.4003 -0.878586)
			)
			(stroke
				(width 0)
				(type default)
			)
			(fill yes)
			(layer "F.SilkS")
		)
		(fp_line
			(start 1.5494 1.1176)
			(end -1.5494 1.1176)
			(stroke
				(width 0.1)
				(type default)
			)
			(layer "F.Fab")
		)
		(fp_line
			(start 1.5494 -1.1176)
			(end 1.5494 1.1176)
			(stroke
				(width 0.1)
				(type default)
			)
			(layer "F.Fab")
		)
		(fp_line
			(start 1.5494 -1.1176)
			(end 0.254 -1.1176)
			(stroke
				(width 0.1)
				(type default)
			)
			(layer "F.Fab")
		)
		(fp_line
			(start 0.254 -1.1176)
			(end -0.254 -1.1176)
			(stroke
				(width 0.1)
				(type default)
			)
			(layer "F.Fab")
		)
		(fp_line
			(start -0.254 -1.1176)
			(end -1.5494 -1.1176)
			(stroke
				(width 0.1)
				(type default)
			)
			(layer "F.Fab")
		)
		(fp_line
			(start -1.5494 1.1176)
			(end -1.5494 -1.1176)
			(stroke
				(width 0.1)
				(type default)
			)
			(layer "F.Fab")
		)
		(fp_poly
			(pts
				(xy -1.8161 -0.675386) (xy -2.4003 -0.446786) (xy -2.4003 -0.878586)
			)
			(stroke
				(width 0)
				(type default)
			)
			(fill yes)
			(layer "F.Fab")
		)
		(pad "1" smd rect
			(at -0.962406 -0.649986 90)
			(size 0.3302 1.1684)
			(layers "F.Cu" "F.Mask" "F.Paste")
			(net "NC_U55_P1")
		)
		(pad "2" smd rect
			(at -0.962406 0 90)
			(size 0.3302 1.1684)
			(layers "F.Cu" "F.Mask" "F.Paste")
			(net "FLASH_LATCH_Q_N_R2")
		)
		(pad "3" smd rect
			(at -0.962406 0.649986 90)
			(size 0.3302 1.1684)
			(layers "F.Cu" "F.Mask" "F.Paste")
			(net "GND")
		)
		(pad "4" smd rect
			(at 0.962406 0.649986 90)
			(size 0.3302 1.1684)
			(layers "F.Cu" "F.Mask" "F.Paste")
			(net "FLASH_R_WP_STATUS")
		)
		(pad "5" smd rect
			(at 0.962406 -0.649986 90)
			(size 0.3302 1.1684)
			(layers "F.Cu" "F.Mask" "F.Paste")
			(net "P3V3_AUX")
		)
	)
	(footprint ""
		(layer "F.Cu")
		(at 46.0756 -109.5248 -90)
		(property "Reference" "R64"
			(at 0 0 270)
			(layer "F.SilkS")
			(hide yes)
			(effects
				(font
					(size 1.27 1.27)
				)
			)
		)
		(property "Value" ""
			(at 0 0 270)
			(layer "F.Fab")
			(effects
				(font
					(size 1.27 1.27)
				)
			)
		)
		(duplicate_pad_numbers_are_jumpers no)
		(fp_line
			(start -0.7874 0.4064)
			(end -0.7874 -0.4064)
			(stroke
				(width 0.1524)
				(type default)
			)
			(layer "F.SilkS")
		)
		(fp_line
			(start 0.7874 0.4064)
			(end -0.7874 0.4064)
			(stroke
				(width 0.1524)
				(type default)
			)
			(layer "F.SilkS")
		)
		(fp_line
			(start -0.7874 -0.4064)
			(end 0.7874 -0.4064)
			(stroke
				(width 0.1524)
				(type default)
			)
			(layer "F.SilkS")
		)
		(fp_line
			(start 0.7874 -0.4064)
			(end 0.7874 0.4064)
			(stroke
				(width 0.1524)
				(type default)
			)
			(layer "F.SilkS")
		)
		(fp_line
			(start -0.67945 0.3048)
			(end -0.67945 -0.305054)
			(stroke
				(width 0.1)
				(type default)
			)
			(layer "F.Fab")
		)
		(fp_line
			(start -0.12065 0.3048)
			(end -0.67945 0.3048)
			(stroke
				(width 0.1)
				(type default)
			)
			(layer "F.Fab")
		)
		(fp_line
			(start 0.120396 0.3048)
			(end 0.120396 0.2794)
			(stroke
				(width 0.1)
				(type default)
			)
			(layer "F.Fab")
		)
		(fp_line
			(start 0.67945 0.3048)
			(end 0.120396 0.3048)
			(stroke
				(width 0.1)
				(type default)
			)
			(layer "F.Fab")
		)
		(fp_line
			(start -0.12065 0.2794)
			(end -0.12065 0.3048)
			(stroke
				(width 0.1)
				(type default)
			)
			(layer "F.Fab")
		)
		(fp_line
			(start 0.120396 0.2794)
			(end -0.12065 0.2794)
			(stroke
				(width 0.1)
				(type default)
			)
			(layer "F.Fab")
		)
		(fp_line
			(start -0.12065 -0.2794)
			(end 0.12065 -0.2794)
			(stroke
				(width 0.1)
				(type default)
			)
			(layer "F.Fab")
		)
		(fp_line
			(start 0.12065 -0.2794)
			(end 0.12065 -0.3048)
			(stroke
				(width 0.1)
				(type default)
			)
			(layer "F.Fab")
		)
		(fp_line
			(start 0.12065 -0.3048)
			(end 0.67945 -0.3048)
			(stroke
				(width 0.1)
				(type default)
			)
			(layer "F.Fab")
		)
		(fp_line
			(start 0.67945 -0.3048)
			(end 0.67945 0.3048)
			(stroke
				(width 0.1)
				(type default)
			)
			(layer "F.Fab")
		)
		(fp_line
			(start -0.67945 -0.305054)
			(end -0.12065 -0.305054)
			(stroke
				(width 0.1)
				(type default)
			)
			(layer "F.Fab")
		)
		(fp_line
			(start -0.12065 -0.305054)
			(end -0.12065 -0.2794)
			(stroke
				(width 0.1)
				(type default)
			)
			(layer "F.Fab")
		)
		(pad "1" smd circle
			(at -0.40005 0 270)
			(size 0 0)
			(layers "F.Cu" "F.Mask" "F.Paste")
			(net "SGPIO_CLK_0")
		)
		(pad "2" smd circle
			(at 0.40005 0 270)
			(size 0 0)
			(layers "F.Cu" "F.Mask" "F.Paste")
			(net "GND")
		)
	)
	(footprint ""
		(layer "F.Cu")
		(at 58.039 -87.9602 90)
		(property "Reference" "R140"
			(at 0 0 90)
			(layer "F.SilkS")
			(hide yes)
			(effects
				(font
					(size 1.27 1.27)
				)
			)
		)
		(property "Value" ""
			(at 0 0 90)
			(layer "F.Fab")
			(effects
				(font
					(size 1.27 1.27)
				)
			)
		)
		(duplicate_pad_numbers_are_jumpers no)
		(fp_line
			(start 0.7874 -0.4064)
			(end 0.7874 0.4064)
			(stroke
				(width 0.1524)
				(type default)
			)
			(layer "F.SilkS")
		)
		(fp_line
			(start -0.7874 -0.4064)
			(end 0.7874 -0.4064)
			(stroke
				(width 0.1524)
				(type default)
			)
			(layer "F.SilkS")
		)
		(fp_line
			(start 0.7874 0.4064)
			(end -0.7874 0.4064)
			(stroke
				(width 0.1524)
				(type default)
			)
			(layer "F.SilkS")
		)
		(fp_line
			(start -0.7874 0.4064)
			(end -0.7874 -0.4064)
			(stroke
				(width 0.1524)
				(type default)
			)
			(layer "F.SilkS")
		)
		(fp_line
			(start -0.12065 -0.305054)
			(end -0.12065 -0.2794)
			(stroke
				(width 0.1)
				(type default)
			)
			(layer "F.Fab")
		)
		(fp_line
			(start -0.67945 -0.305054)
			(end -0.12065 -0.305054)
			(stroke
				(width 0.1)
				(type default)
			)
			(layer "F.Fab")
		)
		(fp_line
			(start 0.67945 -0.3048)
			(end 0.67945 0.3048)
			(stroke
				(width 0.1)
				(type default)
			)
			(layer "F.Fab")
		)
		(fp_line
			(start 0.12065 -0.3048)
			(end 0.67945 -0.3048)
			(stroke
				(width 0.1)
				(type default)
			)
			(layer "F.Fab")
		)
		(fp_line
			(start 0.12065 -0.2794)
			(end 0.12065 -0.3048)
			(stroke
				(width 0.1)
				(type default)
			)
			(layer "F.Fab")
		)
		(fp_line
			(start -0.12065 -0.2794)
			(end 0.12065 -0.2794)
			(stroke
				(width 0.1)
				(type default)
			)
			(layer "F.Fab")
		)
		(fp_line
			(start 0.120396 0.2794)
			(end -0.12065 0.2794)
			(stroke
				(width 0.1)
				(type default)
			)
			(layer "F.Fab")
		)
		(fp_line
			(start -0.12065 0.2794)
			(end -0.12065 0.3048)
			(stroke
				(width 0.1)
				(type default)
			)
			(layer "F.Fab")
		)
		(fp_line
			(start 0.67945 0.3048)
			(end 0.120396 0.3048)
			(stroke
				(width 0.1)
				(type default)
			)
			(layer "F.Fab")
		)
		(fp_line
			(start 0.120396 0.3048)
			(end 0.120396 0.2794)
			(stroke
				(width 0.1)
				(type default)
			)
			(layer "F.Fab")
		)
		(fp_line
			(start -0.12065 0.3048)
			(end -0.67945 0.3048)
			(stroke
				(width 0.1)
				(type default)
			)
			(layer "F.Fab")
		)
		(fp_line
			(start -0.67945 0.3048)
			(end -0.67945 -0.305054)
			(stroke
				(width 0.1)
				(type default)
			)
			(layer "F.Fab")
		)
		(pad "1" smd circle
			(at -0.40005 0 90)
			(size 0 0)
			(layers "F.Cu" "F.Mask" "F.Paste")
			(net "P3V3_AUX")
		)
		(pad "2" smd circle
			(at 0.40005 0 90)
			(size 0 0)
			(layers "F.Cu" "F.Mask" "F.Paste")
			(net "SPI_BMC_BOOT_MOSI")
		)
	)
)
